# BASEBOARD_FAB2 (Tioga Pass) — schematic netlist excerpt (pin names and nets, part order shuffled) for the footprints in the layout excerpt that follows; sources: Cadence DE-HDL packaged netlist, KiCad conversion of Wiwynn_Tioga_Pass_MB.brd

R3U4  RES  120.0 1% CHIP  pkg 0603  page 217 : A = PVDDQ_ABC ; B = GND
R1W33  RES  0.0 5% CHIP  pkg 0402  page 176 : A = SMB_DEBUG_STBY_LVC3_SCL_R1 ; B = SMB_DEBUG_STBY_LVC3_SCL
C1M36  CAP_A  0.01UF 25V 10% X7R  pkg 0402V  page 112 : A = P3V3_STBY ; B = GND

(kicad_pcb
	(version 20260206)
	(generator "pcbnew")
	(generator_version "10.0")
	(general
		(thickness 1.6)
		(legacy_teardrops no)
	)
	(paper "A4")
	(title_block
		(title "Wiwynn_Tioga_Pass_MB.brd")
		(comment 1 "Tioga Pass / footprints 4480-4482 of 4770")
	)
	(layers
		(0 "F.Cu" signal "TOP")
		(4 "In1.Cu" signal "L2GND")
		(6 "In2.Cu" signal "L3")
		(8 "In3.Cu" signal "L4GND")
		(10 "In4.Cu" signal "L5")
		(12 "In5.Cu" signal "L6GND")
		(14 "In6.Cu" signal "L7VCC")
		(16 "In7.Cu" signal "L8VCC")
		(18 "In8.Cu" signal "L9GND")
		(20 "In9.Cu" signal "L10")
		(22 "In10.Cu" signal "L11GND")
		(24 "In11.Cu" signal "L12")
		(26 "In12.Cu" signal "L13GND")
		(2 "B.Cu" signal "BOTTOM")
		(9 "F.Adhes" user "F.Adhesive")
		(11 "B.Adhes" user "B.Adhesive")
		(13 "F.Paste" user "Package Geometry/Pastemask Top")
		(15 "B.Paste" user "Package Geometry/Pastemask Bottom")
		(5 "F.SilkS" user "Ref Des/Silkscreen Top")
		(7 "B.SilkS" user "Ref Des/Silkscreen Bottom")
		(1 "F.Mask" user "Board Geometry/Soldermask Top")
		(3 "B.Mask" user "Board Geometry/Soldermask Bottom")
		(17 "Dwgs.User" user "User.Drawings")
		(19 "Cmts.User" user "User.Comments")
		(21 "Eco1.User" user "User.Eco1")
		(23 "Eco2.User" user "User.Eco2")
		(25 "Edge.Cuts" user "Board Geometry/Outline")
		(27 "Margin" user)
		(31 "F.CrtYd" user "Package Geometry/Place Bound Top")
		(29 "B.CrtYd" user "Package Geometry/Place Bound Bottom")
		(35 "F.Fab" user "Ref Des/Assembly Top")
		(33 "B.Fab" user "Ref Des/Assembly Bottom")
	)
	(footprint ""
		(layer "B.Cu")
		(at 461.7466 -126.7714)
		(property "Reference" "C1M36"
			(at 0 0 0)
			(layer "B.SilkS")
			(hide yes)
			(effects
				(font
					(size 1.27 1.27)
				)
				(justify mirror)
			)
		)
		(property "Value" ""
			(at 0 0 0)
			(layer "B.Fab")
			(effects
				(font
					(size 1.27 1.27)
				)
				(justify mirror)
			)
		)
		(duplicate_pad_numbers_are_jumpers no)
		(fp_poly
			(pts
				(xy -0.3048 -0.1016) (xy -0.3048 0.9906) (xy 0.3048 0.9906) (xy 0.3048 -0.1016)
			)
			(stroke
				(width 0)
				(type default)
			)
			(fill no)
			(layer "B.CrtYd")
		)
		(fp_line
			(start -0.3048 -0.1016)
			(end 0.3048 -0.1016)
			(stroke
				(width 0.1)
				(type default)
			)
			(layer "B.Fab")
		)
		(fp_line
			(start -0.3048 0.9906)
			(end -0.3048 -0.1016)
			(stroke
				(width 0.1)
				(type default)
			)
			(layer "B.Fab")
		)
		(fp_line
			(start 0.3048 -0.1016)
			(end 0.3048 0.9906)
			(stroke
				(width 0.1)
				(type default)
			)
			(layer "B.Fab")
		)
		(fp_line
			(start 0.3048 0.9906)
			(end -0.3048 0.9906)
			(stroke
				(width 0.1)
				(type default)
			)
			(layer "B.Fab")
		)
		(pad "1" smd rect
			(at 0 0 180)
			(size 0.508 0.508)
			(layers "B.Cu" "B.Mask" "B.Paste")
			(net "P3V3_STBY")
		)
		(pad "2" smd rect
			(at 0 0.889 180)
			(size 0.508 0.508)
			(layers "B.Cu" "B.Mask" "B.Paste")
			(net "GND")
		)
		(zone
			(layer "B.Cu")
			(hatch none 0.5)
			(connect_pads
				(clearance 0)
			)
			(min_thickness 0.25)
			(keepout
				(tracks allowed)
				(vias not_allowed)
				(pads allowed)
				(copperpour not_allowed)
				(footprints allowed)
			)
			(placement
				(enabled no)
				(sheetname "")
			)
			(fill
				(thermal_gap 0.5)
				(thermal_bridge_width 0.5)
				(island_removal_mode 0)
			)
			(polygon
				(pts
					(xy 462.0006 -126.5174) (xy 461.4926 -126.5174) (xy 461.4926 -126.1364) (xy 462.0006 -126.1364)
				)
			)
		)
		(zone
			(layer "B.Cu")
			(hatch none 0.5)
			(connect_pads
				(clearance 0)
			)
			(min_thickness 0.25)
			(keepout
				(tracks not_allowed)
				(vias allowed)
				(pads allowed)
				(copperpour not_allowed)
				(footprints allowed)
			)
			(placement
				(enabled no)
				(sheetname "")
			)
			(fill
				(thermal_gap 0.5)
				(thermal_bridge_width 0.5)
				(island_removal_mode 0)
			)
			(polygon
				(pts
					(xy 462.0006 -126.1364) (xy 461.4926 -126.1364) (xy 461.4926 -126.5174) (xy 462.0006 -126.5174)
				)
			)
		)
	)
	(footprint ""
		(layer "B.Cu")
		(at 474.801946 -128.020572 -90)
		(property "Reference" "R1W33"
			(at 0.8382 -0.67818 270)
			(unlocked yes)
			(layer "B.SilkS")
			(effects
				(font
					(size 0.4064 0.254)
					(thickness 0.1524)
				)
				(justify left mirror)
			)
		)
		(property "Value" ""
			(at 0 0 90)
			(layer "B.Fab")
			(effects
				(font
					(size 1.27 1.27)
				)
				(justify mirror)
			)
		)
		(duplicate_pad_numbers_are_jumpers no)
		(fp_poly
			(pts
				(xy 0.2794 -0.1016) (xy -0.2794 -0.1016) (xy -0.2794 0.9906) (xy 0.2794 0.9906)
			)
			(stroke
				(width 0)
				(type default)
			)
			(fill no)
			(layer "B.CrtYd")
		)
		(fp_line
			(start -0.2794 0.9906)
			(end -0.2794 -0.1016)
			(stroke
				(width 0.1)
				(type default)
			)
			(layer "B.Fab")
		)
		(fp_line
			(start 0.2794 0.9906)
			(end -0.2794 0.9906)
			(stroke
				(width 0.1)
				(type default)
			)
			(layer "B.Fab")
		)
		(fp_line
			(start -0.2794 -0.1016)
			(end 0.2794 -0.1016)
			(stroke
				(width 0.1)
				(type default)
			)
			(layer "B.Fab")
		)
		(fp_line
			(start 0.2794 -0.1016)
			(end 0.2794 0.9906)
			(stroke
				(width 0.1)
				(type default)
			)
			(layer "B.Fab")
		)
		(pad "1" smd rect
			(at 0 0 90)
			(size 0.508 0.508)
			(layers "B.Cu" "B.Mask" "B.Paste")
			(net "SMB_DEBUG_STBY_LVC3_SCL_R1")
		)
		(pad "2" smd rect
			(at 0 0.889 90)
			(size 0.508 0.508)
			(layers "B.Cu" "B.Mask" "B.Paste")
			(net "SMB_DEBUG_STBY_LVC3_SCL")
		)
		(zone
			(layer "B.Cu")
			(hatch none 0.5)
			(connect_pads
				(clearance 0)
			)
			(min_thickness 0.25)
			(keepout
				(tracks not_allowed)
				(vias allowed)
				(pads allowed)
				(copperpour not_allowed)
				(footprints allowed)
			)
			(placement
				(enabled no)
				(sheetname "")
			)
			(fill
				(thermal_gap 0.5)
				(thermal_bridge_width 0.5)
				(island_removal_mode 0)
			)
			(polygon
				(pts
					(xy 474.166946 -127.766572) (xy 474.166946 -128.274572) (xy 474.547946 -128.274572) (xy 474.547946 -127.766572)
				)
			)
		)
		(zone
			(layer "B.Cu")
			(hatch none 0.5)
			(connect_pads
				(clearance 0)
			)
			(min_thickness 0.25)
			(keepout
				(tracks allowed)
				(vias not_allowed)
				(pads allowed)
				(copperpour not_allowed)
				(footprints allowed)
			)
			(placement
				(enabled no)
				(sheetname "")
			)
			(fill
				(thermal_gap 0.5)
				(thermal_bridge_width 0.5)
				(island_removal_mode 0)
			)
			(polygon
				(pts
					(xy 474.547946 -127.766572) (xy 474.547946 -128.274572) (xy 474.166946 -128.274572) (xy 474.166946 -127.766572)
				)
			)
		)
	)
	(footprint ""
		(layer "B.Cu")
		(at 338.328 -11.938 90)
		(property "Reference" "R3U4"
			(at 0 0 90)
			(layer "B.SilkS")
			(hide yes)
			(effects
				(font
					(size 1.27 1.27)
				)
				(justify mirror)
			)
		)
		(property "Value" ""
			(at 0 0 90)
			(layer "B.Fab")
			(effects
				(font
					(size 1.27 1.27)
				)
				(justify mirror)
			)
		)
		(duplicate_pad_numbers_are_jumpers no)
		(fp_rect
			(start 0.4953 1.6002)
			(end -0.4953 -0.2032)
			(stroke
				(width 0)
				(type default)
			)
			(fill no)
			(layer "B.CrtYd")
		)
		(fp_line
			(start 0.4953 -0.2032)
			(end -0.4953 -0.2032)
			(stroke
				(width 0.1)
				(type default)
			)
			(layer "B.Fab")
		)
		(fp_line
			(start -0.4953 -0.2032)
			(end -0.4953 1.6002)
			(stroke
				(width 0.1)
				(type default)
			)
			(layer "B.Fab")
		)
		(fp_line
			(start 0.4953 1.6002)
			(end 0.4953 -0.2032)
			(stroke
				(width 0.1)
				(type default)
			)
			(layer "B.Fab")
		)
		(fp_line
			(start -0.4953 1.6002)
			(end 0.4953 1.6002)
			(stroke
				(width 0.1)
				(type default)
			)
			(layer "B.Fab")
		)
		(pad "1" smd rect
			(at 0 0 270)
			(size 0.762 0.889)
			(layers "B.Cu" "B.Mask" "B.Paste")
			(net "PVDDQ_ABC")
		)
		(pad "2" smd rect
			(at 0 1.397 270)
			(size 0.762 0.889)
			(layers "B.Cu" "B.Mask" "B.Paste")
			(net "GND")
		)
		(zone
			(layer "B.Cu")
			(hatch none 0.5)
			(connect_pads
				(clearance 0)
			)
			(min_thickness 0.25)
			(keepout
				(tracks not_allowed)
				(vias allowed)
				(pads allowed)
				(copperpour not_allowed)
				(footprints allowed)
			)
			(placement
				(enabled no)
				(sheetname "")
			)
			(fill
				(thermal_gap 0.5)
				(thermal_bridge_width 0.5)
				(island_removal_mode 0)
			)
			(polygon
				(pts
					(xy 339.2805 -12.319) (xy 338.7725 -12.319) (xy 338.7725 -11.557) (xy 339.2805 -11.557)
				)
			)
		)
		(zone
			(layer "B.Cu")
			(hatch none 0.5)
			(connect_pads
				(clearance 0)
			)
			(min_thickness 0.25)
			(keepout
				(tracks allowed)
				(vias not_allowed)
				(pads allowed)
				(copperpour not_allowed)
				(footprints allowed)
			)
			(placement
				(enabled no)
				(sheetname "")
			)
			(fill
				(thermal_gap 0.5)
				(thermal_bridge_width 0.5)
				(island_removal_mode 0)
			)
			(polygon
				(pts
					(xy 339.2805 -12.319) (xy 338.7725 -12.319) (xy 338.7725 -11.557) (xy 339.2805 -11.557)
				)
			)
		)
	)
)
